# S9S_MB_2U (Grand Teton) — schematic netlist excerpt (pin names and nets, part order shuffled) for the footprints in the layout excerpt that follows; sources: Cadence DE-HDL packaged netlist, KiCad conversion of 03242023_DA0F0TMBIJ0_F0T_Motherboard_J_brd_V01_OCP.brd

PU31_P1_1  ISL99390FRZTR5935  ISL99390FRZ-TR5935 IC  pkg QFN21_6X5XB  page 285
  VOS  = PVCCIN_CPU1_VOS1
  AGND  = GND
  VCC  = PVCCIN_CPU1_VDD1
  PVCC  = PVCCIN_CPU1_PVCC
  PGND1  = GND
  GL1  = NC
  PGND2  = GND
  SW  = SW_PVCCIN_CPU1_SW1
  VIN1  = SW_P12V_PVCCIN_CPU1_FLT
  VIN2  = SW_P12V_PVCCIN_CPU1_FLT
  DNC  = NC
  PHASE  = SW_PVCCIN_CPU1_BOOTR1
  BOOT  = SW_PVCCIN_CPU1_BOOT1
  PWM  = PVCCIN_CPU1_PWM1
  EN  = PVCCIN_CPU1_VDD1
  TOUT_FLT  = PVCCIN_CPU1_ATSEN
  LSET  = PVCCIN_CPU1_LSET1
  IOUT  = PVCCIN_CPU1_IMON1
  REFIN  = PVCCIN_CPU1_VREF
  PGND3  = GND
  GL2  = NC

(kicad_pcb
	(version 20260206)
	(generator "pcbnew")
	(generator_version "10.0")
	(general
		(thickness 1.6)
		(legacy_teardrops no)
	)
	(paper "A4")
	(title_block
		(title "03242023_DA0F0TMBIJ0_F0T_Motherboard_J_brd_V01_OCP.brd")
		(comment 1 "Grand Teton / footprints 3312-3312 of 6105")
	)
	(layers
		(0 "F.Cu" signal "TOP")
		(4 "In1.Cu" signal "GND")
		(6 "In2.Cu" signal "IN1")
		(8 "In3.Cu" signal "GND1")
		(10 "In4.Cu" signal "IN2")
		(12 "In5.Cu" signal "GND2")
		(14 "In6.Cu" signal "IN3")
		(16 "In7.Cu" signal "GND3")
		(18 "In8.Cu" signal "VCC")
		(20 "In9.Cu" signal "VCC1")
		(22 "In10.Cu" signal "GND4")
		(24 "In11.Cu" signal "IN4")
		(26 "In12.Cu" signal "GND5")
		(28 "In13.Cu" signal "IN5")
		(30 "In14.Cu" signal "GND6")
		(32 "In15.Cu" signal "IN6")
		(34 "In16.Cu" signal "GND7")
		(2 "B.Cu" signal "BOTTOM")
		(9 "F.Adhes" user "F.Adhesive")
		(11 "B.Adhes" user "B.Adhesive")
		(13 "F.Paste" user "Package Geometry/Pastemask Top")
		(15 "B.Paste" user "Package Geometry/Pastemask Bottom")
		(5 "F.SilkS" user "Ref Des/Silkscreen Top")
		(7 "B.SilkS" user "Ref Des/Silkscreen Bottom")
		(1 "F.Mask" user "Board Geometry/Soldermask Top")
		(3 "B.Mask" user "Board Geometry/Soldermask Bottom")
		(17 "Dwgs.User" user "User.Drawings")
		(19 "Cmts.User" user "User.Comments")
		(21 "Eco1.User" user "User.Eco1")
		(23 "Eco2.User" user "User.Eco2")
		(25 "Edge.Cuts" user "Board Geometry/Outline")
		(27 "Margin" user)
		(31 "F.CrtYd" user "Package Geometry/Place Bound Top")
		(29 "B.CrtYd" user "Package Geometry/Place Bound Bottom")
		(35 "F.Fab" user "Ref Des/Assembly Top")
		(33 "B.Fab" user "Ref Des/Assembly Bottom")
	)
	(footprint ""
		(layer "F.Cu")
		(at 96.997774 -333.716122)
		(property "Reference" "PU31_P1_1"
			(at -2.685796 -6.321298 0)
			(unlocked yes)
			(layer "F.SilkS")
			(effects
				(font
					(size 0.7874 0.5842)
					(thickness 0.1524)
				)
				(justify left)
			)
		)
		(property "Value" ""
			(at 0 0 0)
			(layer "F.Fab")
			(effects
				(font
					(size 1.27 1.27)
				)
			)
		)
		(duplicate_pad_numbers_are_jumpers no)
		(fp_line
			(start -2.500122 -2.999994)
			(end -2.24409 -2.999994)
			(stroke
				(width 0.1524)
				(type default)
			)
			(layer "F.SilkS")
		)
		(fp_line
			(start -2.500122 -2.529078)
			(end -2.500122 -2.999994)
			(stroke
				(width 0.1524)
				(type default)
			)
			(layer "F.SilkS")
		)
		(fp_line
			(start -2.500122 0.6604)
			(end -2.500122 0.229108)
			(stroke
				(width 0.1524)
				(type default)
			)
			(layer "F.SilkS")
		)
		(fp_line
			(start -2.500122 2.999994)
			(end -2.500122 2.339594)
			(stroke
				(width 0.1524)
				(type default)
			)
			(layer "F.SilkS")
		)
		(fp_line
			(start -2.2987 2.999994)
			(end -2.500122 2.999994)
			(stroke
				(width 0.1524)
				(type default)
			)
			(layer "F.SilkS")
		)
		(fp_line
			(start 2.31394 -2.999994)
			(end 2.500122 -2.999994)
			(stroke
				(width 0.1524)
				(type default)
			)
			(layer "F.SilkS")
		)
		(fp_line
			(start 2.500122 -2.999994)
			(end 2.500122 -2.44348)
			(stroke
				(width 0.1524)
				(type default)
			)
			(layer "F.SilkS")
		)
		(fp_line
			(start 2.500122 2.339594)
			(end 2.500122 2.999994)
			(stroke
				(width 0.1524)
				(type default)
			)
			(layer "F.SilkS")
		)
		(fp_line
			(start 2.500122 2.999994)
			(end 2.2987 2.999994)
			(stroke
				(width 0.1524)
				(type default)
			)
			(layer "F.SilkS")
		)
		(fp_poly
			(pts
				(xy -2.162302 -3.588004) (xy -2.670302 -2.572004) (xy -3.178302 -3.588004)
			)
			(stroke
				(width 0)
				(type default)
			)
			(fill yes)
			(layer "F.SilkS")
		)
		(fp_line
			(start -2.500122 -2.999994)
			(end 2.500122 -2.999994)
			(stroke
				(width 0.1)
				(type default)
			)
			(layer "F.Fab")
		)
		(fp_line
			(start -2.500122 2.999994)
			(end -2.500122 -2.999994)
			(stroke
				(width 0.1)
				(type default)
			)
			(layer "F.Fab")
		)
		(fp_line
			(start 2.500122 -2.999994)
			(end 2.500122 2.999994)
			(stroke
				(width 0.1)
				(type default)
			)
			(layer "F.Fab")
		)
		(fp_line
			(start 2.500122 2.999994)
			(end -2.500122 2.999994)
			(stroke
				(width 0.1)
				(type default)
			)
			(layer "F.Fab")
		)
		(fp_poly
			(pts
				(xy -4.218432 -2.783078) (xy -4.218432 -1.767078) (xy -3.202432 -2.275078)
			)
			(stroke
				(width 0)
				(type default)
			)
			(fill yes)
			(layer "F.Fab")
		)
		(pad "1" smd rect
			(at -2.400046 -2.275078 90)
			(size 0.2286 0.6096)
			(layers "F.Cu" "F.Mask" "F.Paste")
			(net "PVCCIN_CPU1_VOS1")
		)
		(pad "2" smd rect
			(at -2.400046 -1.82499 90)
			(size 0.2286 0.6096)
			(layers "F.Cu" "F.Mask" "F.Paste")
			(net "GND")
		)
		(pad "3" smd rect
			(at -2.400046 -1.374902 90)
			(size 0.2286 0.6096)
			(layers "F.Cu" "F.Mask" "F.Paste")
			(net "PVCCIN_CPU1_VDD1")
		)
		(pad "4" smd rect
			(at -2.400046 -0.925068 90)
			(size 0.2286 0.6096)
			(layers "F.Cu" "F.Mask" "F.Paste")
			(net "PVCCIN_CPU1_PVCC")
		)
		(pad "5" smd rect
			(at -2.400046 -0.47498 90)
			(size 0.2286 0.6096)
			(layers "F.Cu" "F.Mask" "F.Paste")
			(net "GND")
		)
		(pad "6" smd rect
			(at -2.400046 -0.024892 90)
			(size 0.2286 0.6096)
			(layers "F.Cu" "F.Mask" "F.Paste")
			(net "Net_8520")
		)
		(pad "7_9-20_24" smd circle
			(at 0 1.150112 90)
			(size 0 0)
			(layers "F.Cu" "F.Mask" "F.Paste")
			(net "GND")
		)
		(pad "10_19" smd rect
			(at 0 2.899918 90)
			(size 0.6096 4.318)
			(layers "F.Cu" "F.Mask" "F.Paste")
			(net "SW_PVCCIN_CPU1_SW1")
		)
		(pad "25_29" smd rect
			(at 1.549908 -1.279906 270)
			(size 2.0574 2.3114)
			(layers "F.Cu" "F.Mask" "F.Paste")
			(net "SW_P12V_PVCCIN_CPU1_FLT")
		)
		(pad "30" smd rect
			(at 2.05994 -2.899918)
			(size 0.2286 0.6096)
			(layers "F.Cu" "F.Mask" "F.Paste")
			(net "SW_P12V_PVCCIN_CPU1_FLT")
		)
		(pad "31" smd rect
			(at 1.610106 -2.899918)
			(size 0.2286 0.6096)
			(layers "F.Cu" "F.Mask" "F.Paste")
			(net "Net_8521")
		)
		(pad "32" smd rect
			(at 1.160018 -2.899918)
			(size 0.2286 0.6096)
			(layers "F.Cu" "F.Mask" "F.Paste")
			(net "SW_PVCCIN_CPU1_BOOTR1")
		)
		(pad "33" smd rect
			(at 0.70993 -2.899918)
			(size 0.2286 0.6096)
			(layers "F.Cu" "F.Mask" "F.Paste")
			(net "SW_PVCCIN_CPU1_BOOT1")
		)
		(pad "34" smd rect
			(at 0.260096 -2.899918)
			(size 0.2286 0.6096)
			(layers "F.Cu" "F.Mask" "F.Paste")
			(net "PVCCIN_CPU1_PWM1")
		)
		(pad "35" smd rect
			(at -0.189992 -2.899918)
			(size 0.2286 0.6096)
			(layers "F.Cu" "F.Mask" "F.Paste")
			(net "PVCCIN_CPU1_VDD1")
		)
		(pad "36" smd rect
			(at -0.64008 -2.899918)
			(size 0.2286 0.6096)
			(layers "F.Cu" "F.Mask" "F.Paste")
			(net "PVCCIN_CPU1_ATSEN")
		)
		(pad "37" smd rect
			(at -1.089914 -2.899918)
			(size 0.2286 0.6096)
			(layers "F.Cu" "F.Mask" "F.Paste")
			(net "PVCCIN_CPU1_LSET1")
		)
		(pad "38" smd rect
			(at -1.540002 -2.899918)
			(size 0.2286 0.6096)
			(layers "F.Cu" "F.Mask" "F.Paste")
			(net "PVCCIN_CPU1_IMON1")
		)
		(pad "39" smd rect
			(at -1.99009 -2.899918)
			(size 0.2286 0.6096)
			(layers "F.Cu" "F.Mask" "F.Paste")
			(net "PVCCIN_CPU1_VREF")
		)
		(pad "40" smd rect
			(at -0.87503 -1.27508)
			(size 1.7526 1.9558)
			(layers "F.Cu" "F.Mask" "F.Paste")
			(net "GND")
		)
		(pad "41" smd rect
			(at -1.525016 0.249936 270)
			(size 0.3048 0.4572)
			(layers "F.Cu" "F.Mask" "F.Paste")
			(net "Net_8519")
		)
		(zone
			(layer "F.Cu")
			(hatch none 0.5)
			(connect_pads
				(clearance 0)
			)
			(min_thickness 0.25)
			(keepout
				(tracks not_allowed)
				(vias allowed)
				(pads allowed)
				(copperpour not_allowed)
				(footprints allowed)
			)
			(placement
				(enabled no)
				(sheetname "")
			)
			(fill
				(thermal_gap 0.5)
				(thermal_bridge_width 0.5)
				(island_removal_mode 0)
			)
			(polygon
				(pts
					(xy 94.497652 -330.716128) (xy 94.497652 -331.465428) (xy 99.497896 -331.465428) (xy 99.497896 -330.716128)
					(xy 99.207574 -330.716128) (xy 99.207574 -331.171804) (xy 94.787974 -331.171804) (xy 94.787974 -330.716128)
				)
			)
		)
		(zone
			(layer "F.Cu")
			(hatch none 0.5)
			(connect_pads
				(clearance 0)
			)
			(min_thickness 0.25)
			(keepout
				(tracks not_allowed)
				(vias allowed)
				(pads allowed)
				(copperpour not_allowed)
				(footprints allowed)
			)
			(placement
				(enabled no)
				(sheetname "")
			)
			(fill
				(thermal_gap 0.5)
				(thermal_bridge_width 0.5)
				(island_removal_mode 0)
			)
			(polygon
				(pts
					(xy 94.953328 -334.040988) (xy 95.195644 -334.040988) (xy 95.195644 -333.962502) (xy 95.96374 -333.962502)
					(xy 95.96374 -333.637128) (xy 96.047052 -333.637128) (xy 96.047052 -332.966822) (xy 94.497652 -332.966822)
					(xy 94.497652 -333.423514) (xy 95.193358 -333.423514) (xy 95.193358 -333.262986) (xy 95.752158 -333.262986)
					(xy 95.752158 -333.669386) (xy 95.193358 -333.669386) (xy 95.193358 -333.448914) (xy 94.497652 -333.448914)
					(xy 94.497652 -333.575914) (xy 94.953328 -333.575914)
				)
			)
		)
	)
)
